(kicad_pcb
	(version 20241229)
	(generator "pcbnew")
	(generator_version "9.0")
	(general
		(thickness 1.6296)
		(legacy_teardrops no)
	)
	(paper "A3")
	(title_block
		(title "Thunderbolt to 10GbE adapter")
		(date "2026-04-21")
		(rev "1.1.0")
		(company "Antmicro Ltd")
		(comment 1 "www.antmicro.com")
		(comment 9 "footprints 593-597 of 703")
	)
	(layers
		(0 "F.Cu" signal)
		(4 "In1.Cu" signal)
		(6 "In2.Cu" signal)
		(8 "In3.Cu" signal)
		(10 "In4.Cu" signal)
		(12 "In5.Cu" signal)
		(14 "In6.Cu" signal)
		(2 "B.Cu" signal)
		(9 "F.Adhes" user "F.Adhesive")
		(11 "B.Adhes" user "B.Adhesive")
		(13 "F.Paste" user)
		(15 "B.Paste" user)
		(5 "F.SilkS" user "F.Silkscreen")
		(7 "B.SilkS" user "B.Silkscreen")
		(1 "F.Mask" user)
		(3 "B.Mask" user)
		(17 "Dwgs.User" user "User.Drawings")
		(19 "Cmts.User" user "User.Comments")
		(21 "Eco1.User" user "User.Eco1")
		(23 "Eco2.User" user "User.Eco2")
		(25 "Edge.Cuts" user)
		(27 "Margin" user)
		(31 "F.CrtYd" user "F.Courtyard")
		(29 "B.CrtYd" user "B.Courtyard")
		(35 "F.Fab" user)
		(33 "B.Fab" user)
	)
	(footprint "antmicro-footprints:C_0402_1005Metric"
		(layer "B.Cu")
		(at 126.8 142.3 -90)
		(descr "Capacitor SMD 0402")
		(tags "capacitor SMD 0402")
		(property "Reference" "C31"
			(at -1.15 -2.45 90)
			(layer "B.SilkS")
			(effects
				(font
					(size 0.7 0.7)
					(thickness 0.15)
				)
				(justify left bottom mirror)
			)
		)
		(property "Value" "C_220p_0402"
			(at -1.022927 -2.155213 90)
			(layer "B.Fab")
			(effects
				(font
					(size 0.7 0.7)
					(thickness 0.15)
				)
				(justify left bottom mirror)
			)
		)
		(property "Datasheet" "https://spicat.kyocera-avx.com/product/mlcc/chartview/04025C221JAT2A/"
			(at 0 0 90)
			(layer "B.Fab")
			(hide yes)
			(effects
				(font
					(size 1.27 1.27)
					(thickness 0.15)
				)
				(justify mirror)
			)
		)
		(property "Description" "SMD Multilayer Ceramic Capacitor, 220 pF, 50 V, 0402 [1005 Metric], ± 10%, X7R, MC"
			(at 0 0 90)
			(layer "B.Fab")
			(hide yes)
			(effects
				(font
					(size 1.27 1.27)
					(thickness 0.15)
				)
				(justify mirror)
			)
		)
		(property "MPN" "04025C221JAT2A"
			(at 0 0 270)
			(unlocked yes)
			(layer "B.Fab")
			(hide yes)
			(effects
				(font
					(size 1 1)
					(thickness 0.15)
				)
				(justify mirror)
			)
		)
		(property "Manufacturer" "KYOCERA AVX"
			(at 0 0 270)
			(unlocked yes)
			(layer "B.Fab")
			(hide yes)
			(effects
				(font
					(size 1 1)
					(thickness 0.15)
				)
				(justify mirror)
			)
		)
		(property "License" "Apache-2.0"
			(at 0 0 270)
			(unlocked yes)
			(layer "B.Fab")
			(hide yes)
			(effects
				(font
					(size 1 1)
					(thickness 0.15)
				)
				(justify mirror)
			)
		)
		(property "Val" "220p"
			(at 0 0 270)
			(unlocked yes)
			(layer "B.Fab")
			(hide yes)
			(effects
				(font
					(size 1 1)
					(thickness 0.15)
				)
				(justify mirror)
			)
		)
		(property "Voltage" ""
			(at 0 0 270)
			(unlocked yes)
			(layer "B.Fab")
			(hide yes)
			(effects
				(font
					(size 1 1)
					(thickness 0.15)
				)
				(justify mirror)
			)
		)
		(property "Dielectric" ""
			(at 0 0 270)
			(unlocked yes)
			(layer "B.Fab")
			(hide yes)
			(effects
				(font
					(size 1 1)
					(thickness 0.15)
				)
				(justify mirror)
			)
		)
		(property "Author" "Antmicro"
			(at 0 0 270)
			(unlocked yes)
			(layer "B.Fab")
			(hide yes)
			(effects
				(font
					(size 1 1)
					(thickness 0.15)
				)
				(justify mirror)
			)
		)
		(sheetname "/PD and TB DC-DC/")
		(sheetfile "PD_and_TB_DC_DC.kicad_sch")
		(attr smd)
		(fp_rect
			(start -0.925 0.47)
			(end 0.925 -0.47)
			(stroke
				(width 0.05)
				(type default)
			)
			(fill no)
			(layer "B.CrtYd")
		)
		(fp_line
			(start -0.494 0.25)
			(end 0.504 0.25)
			(stroke
				(width 0.15)
				(type solid)
			)
			(layer "B.Fab")
		)
		(fp_line
			(start 0.504 0.25)
			(end 0.504 -0.248)
			(stroke
				(width 0.15)
				(type solid)
			)
			(layer "B.Fab")
		)
		(fp_line
			(start -0.494 -0.248)
			(end -0.494 0.25)
			(stroke
				(width 0.15)
				(type solid)
			)
			(layer "B.Fab")
		)
		(fp_line
			(start 0.504 -0.248)
			(end -0.494 -0.248)
			(stroke
				(width 0.15)
				(type solid)
			)
			(layer "B.Fab")
		)
		(fp_text user "${REFERENCE}"
			(at -0.939 -4.599 90)
			(layer "B.Fab")
			(effects
				(font
					(size 0.7 0.7)
					(thickness 0.15)
				)
				(justify left bottom mirror)
			)
		)
		(fp_text user "Author: Antmicro"
			(at -0.939 -3.399 90)
			(layer "B.Fab")
			(effects
				(font
					(size 0.7 0.7)
					(thickness 0.15)
				)
				(justify left bottom mirror)
			)
		)
		(fp_text user "License: Apache-2.0"
			(at -0.939 -5.799 90)
			(layer "B.Fab")
			(effects
				(font
					(size 0.7 0.7)
					(thickness 0.15)
				)
				(justify left bottom mirror)
			)
		)
		(pad "1" smd roundrect
			(at -0.48 0 270)
			(size 0.59 0.64)
			(layers "B.Cu" "B.Mask" "B.Paste")
			(roundrect_rratio 0.25)
			(net 23 "GND")
			(pintype "passive")
		)
		(pad "2" smd roundrect
			(at 0.48 0 270)
			(size 0.59 0.64)
			(layers "B.Cu" "B.Mask" "B.Paste")
			(roundrect_rratio 0.25)
			(net 306 "/PD and TB DC-DC/USB3.CC1")
			(pintype "passive")
		)
	)
	(footprint "antmicro-footprints:C_0402_1005Metric"
		(layer "B.Cu")
		(at 125.574999 123.95 -90)
		(descr "Capacitor SMD 0402")
		(tags "capacitor SMD 0402")
		(property "Reference" "C60"
			(at -7.700002 -21.900002 90)
			(layer "B.SilkS")
			(effects
				(font
					(size 0.7 0.7)
					(thickness 0.15)
				)
				(justify mirror)
			)
		)
		(property "Value" "C_1u_0402"
			(at -1.022927 -2.155213 90)
			(layer "B.Fab")
			(effects
				(font
					(size 0.7 0.7)
					(thickness 0.15)
				)
				(justify left bottom mirror)
			)
		)
		(property "Datasheet" "https://product.tdk.com/en/search/capacitor/ceramic/mlcc/info?part_no=C1005X6S1A105K050BC"
			(at 0 0 90)
			(layer "B.Fab")
			(hide yes)
			(effects
				(font
					(size 1.27 1.27)
					(thickness 0.15)
				)
				(justify mirror)
			)
		)
		(property "Description" "SMD Multilayer Ceramic Capacitor, 1 µF, 10 V, 0402 [1005 Metric], ± 10%, X6S, C"
			(at 0 0 90)
			(layer "B.Fab")
			(hide yes)
			(effects
				(font
					(size 1.27 1.27)
					(thickness 0.15)
				)
				(justify mirror)
			)
		)
		(property "MPN" "C1005X6S1A105K050BC"
			(at 0 0 270)
			(unlocked yes)
			(layer "B.Fab")
			(hide yes)
			(effects
				(font
					(size 1 1)
					(thickness 0.15)
				)
				(justify mirror)
			)
		)
		(property "Manufacturer" "TDK"
			(at 0 0 270)
			(unlocked yes)
			(layer "B.Fab")
			(hide yes)
			(effects
				(font
					(size 1 1)
					(thickness 0.15)
				)
				(justify mirror)
			)
		)
		(property "License" "Apache-2.0"
			(at 0 0 270)
			(unlocked yes)
			(layer "B.Fab")
			(hide yes)
			(effects
				(font
					(size 1 1)
					(thickness 0.15)
				)
				(justify mirror)
			)
		)
		(property "Val" "1u"
			(at 0 0 270)
			(unlocked yes)
			(layer "B.Fab")
			(hide yes)
			(effects
				(font
					(size 1 1)
					(thickness 0.15)
				)
				(justify mirror)
			)
		)
		(property "Voltage" ""
			(at 0 0 270)
			(unlocked yes)
			(layer "B.Fab")
			(hide yes)
			(effects
				(font
					(size 1 1)
					(thickness 0.15)
				)
				(justify mirror)
			)
		)
		(property "Dielectric" ""
			(at 0 0 270)
			(unlocked yes)
			(layer "B.Fab")
			(hide yes)
			(effects
				(font
					(size 1 1)
					(thickness 0.15)
				)
				(justify mirror)
			)
		)
		(property "Author" "Antmicro"
			(at 0 0 270)
			(unlocked yes)
			(layer "B.Fab")
			(hide yes)
			(effects
				(font
					(size 1 1)
					(thickness 0.15)
				)
				(justify mirror)
			)
		)
		(sheetname "/TB Controller - Power/")
		(sheetfile "tb-power.kicad_sch")
		(attr smd)
		(fp_rect
			(start -0.925 0.47)
			(end 0.925 -0.47)
			(stroke
				(width 0.05)
				(type default)
			)
			(fill no)
			(layer "B.CrtYd")
		)
		(fp_line
			(start -0.494 0.25)
			(end 0.504 0.25)
			(stroke
				(width 0.15)
				(type solid)
			)
			(layer "B.Fab")
		)
		(fp_line
			(start 0.504 0.25)
			(end 0.504 -0.248)
			(stroke
				(width 0.15)
				(type solid)
			)
			(layer "B.Fab")
		)
		(fp_line
			(start -0.494 -0.248)
			(end -0.494 0.25)
			(stroke
				(width 0.15)
				(type solid)
			)
			(layer "B.Fab")
		)
		(fp_line
			(start 0.504 -0.248)
			(end -0.494 -0.248)
			(stroke
				(width 0.15)
				(type solid)
			)
			(layer "B.Fab")
		)
		(fp_text user "${REFERENCE}"
			(at -0.939 -4.599 90)
			(layer "B.Fab")
			(effects
				(font
					(size 0.7 0.7)
					(thickness 0.15)
				)
				(justify left bottom mirror)
			)
		)
		(fp_text user "Author: Antmicro"
			(at -0.939 -3.399 90)
			(layer "B.Fab")
			(effects
				(font
					(size 0.7 0.7)
					(thickness 0.15)
				)
				(justify left bottom mirror)
			)
		)
		(fp_text user "License: Apache-2.0"
			(at -0.939 -5.799 90)
			(layer "B.Fab")
			(effects
				(font
					(size 0.7 0.7)
					(thickness 0.15)
				)
				(justify left bottom mirror)
			)
		)
		(pad "1" smd roundrect
			(at -0.48 0 270)
			(size 0.59 0.64)
			(layers "B.Cu" "B.Mask" "B.Paste")
			(roundrect_rratio 0.25)
			(net 23 "GND")
			(pintype "passive")
		)
		(pad "2" smd roundrect
			(at 0.48 0 270)
			(size 0.59 0.64)
			(layers "B.Cu" "B.Mask" "B.Paste")
			(roundrect_rratio 0.25)
			(net 403 "Net-(C55-Pad2)")
			(pintype "passive")
		)
	)
	(footprint "antmicro-footprints:R_0402_1005Metric"
		(layer "B.Cu")
		(at 149.331866 75.285117)
		(descr "Resistor SMD 0402")
		(tags "resistor SMD 0402")
		(property "Reference" "R130"
			(at 19.468135 9.464883 180)
			(layer "B.SilkS")
			(effects
				(font
					(size 0.7 0.7)
					(thickness 0.15)
				)
				(justify mirror)
			)
		)
		(property "Value" "R_100R_0402"
			(at -1.011843 -1.772047 180)
			(layer "B.Fab")
			(effects
				(font
					(size 0.7 0.7)
					(thickness 0.15)
				)
				(justify left bottom mirror)
			)
		)
		(property "Datasheet" "https://www.bourns.com/docs/product-datasheets/cr.pdf"
			(at 0 0 180)
			(layer "B.Fab")
			(hide yes)
			(effects
				(font
					(size 1.27 1.27)
					(thickness 0.15)
				)
				(justify mirror)
			)
		)
		(property "Description" "SMD Chip Resistor, 100 ohm, ± 1%, 62.5 mW, 0402 [1005 Metric], Thick Film, General Purpose"
			(at 0 0 180)
			(layer "B.Fab")
			(hide yes)
			(effects
				(font
					(size 1.27 1.27)
					(thickness 0.15)
				)
				(justify mirror)
			)
		)
		(property "MPN" "CR0402-FX-1000GLF"
			(at 0 0 0)
			(unlocked yes)
			(layer "B.Fab")
			(hide yes)
			(effects
				(font
					(size 1 1)
					(thickness 0.15)
				)
				(justify mirror)
			)
		)
		(property "Manufacturer" "Bourns"
			(at 0 0 0)
			(unlocked yes)
			(layer "B.Fab")
			(hide yes)
			(effects
				(font
					(size 1 1)
					(thickness 0.15)
				)
				(justify mirror)
			)
		)
		(property "License" "Apache-2.0"
			(at 0 0 0)
			(unlocked yes)
			(layer "B.Fab")
			(hide yes)
			(effects
				(font
					(size 1 1)
					(thickness 0.15)
				)
				(justify mirror)
			)
		)
		(property "Author" "Antmicro"
			(at 0 0 0)
			(unlocked yes)
			(layer "B.Fab")
			(hide yes)
			(effects
				(font
					(size 1 1)
					(thickness 0.15)
				)
				(justify mirror)
			)
		)
		(property "Val" "100R"
			(at 0 0 0)
			(unlocked yes)
			(layer "B.Fab")
			(hide yes)
			(effects
				(font
					(size 1 1)
					(thickness 0.15)
				)
				(justify mirror)
			)
		)
		(property "Tolerance" "1%"
			(at 0 0 0)
			(unlocked yes)
			(layer "B.Fab")
			(hide yes)
			(effects
				(font
					(size 1 1)
					(thickness 0.15)
				)
				(justify mirror)
			)
		)
		(sheetname "/X710-AT2 RSVD/")
		(sheetfile "x710-at2-rsvd.kicad_sch")
		(attr smd)
		(fp_rect
			(start -0.925 0.47)
			(end 0.925 -0.47)
			(stroke
				(width 0.05)
				(type default)
			)
			(fill no)
			(layer "B.CrtYd")
		)
		(fp_rect
			(start -0.5 0.25)
			(end 0.5 -0.25)
			(stroke
				(width 0.15)
				(type solid)
			)
			(fill no)
			(layer "B.Fab")
		)
		(fp_text user "License: Apache-2.0"
			(at -0.95 -5.169 180)
			(layer "B.Fab")
			(effects
				(font
					(size 0.7 0.7)
					(thickness 0.15)
				)
				(justify left bottom mirror)
			)
		)
		(fp_text user "${REFERENCE}"
			(at -0.95 -3.168 180)
			(layer "B.Fab")
			(effects
				(font
					(size 0.7 0.7)
					(thickness 0.15)
				)
				(justify left bottom mirror)
			)
		)
		(fp_text user "Author: Antmicro"
			(at -0.95 -4.169 180)
			(layer "B.Fab")
			(effects
				(font
					(size 0.7 0.7)
					(thickness 0.15)
				)
				(justify left bottom mirror)
			)
		)
		(pad "1" smd roundrect
			(at -0.48 0)
			(size 0.59 0.64)
			(layers "B.Cu" "B.Mask" "B.Paste")
			(roundrect_rratio 0.25)
			(net 23 "GND")
			(pintype "passive")
		)
		(pad "2" smd roundrect
			(at 0.48 0)
			(size 0.59 0.64)
			(layers "B.Cu" "B.Mask" "B.Paste")
			(roundrect_rratio 0.25)
			(net 99 "/X710-AT2 RSVD/RSVDP8_VSS")
			(pintype "passive")
		)
	)
	(footprint "antmicro-footprints:R_0402_1005Metric"
		(layer "B.Cu")
		(at 138.450001 116.125001)
		(descr "Resistor SMD 0402")
		(tags "resistor SMD 0402")
		(property "Reference" "R46"
			(at 19.525001 -7.450001 180)
			(layer "B.SilkS")
			(effects
				(font
					(size 0.7 0.7)
					(thickness 0.15)
				)
				(justify mirror)
			)
		)
		(property "Value" "R_10k_0402"
			(at -1.011843 -1.772047 180)
			(layer "B.Fab")
			(effects
				(font
					(size 0.7 0.7)
					(thickness 0.15)
				)
				(justify left bottom mirror)
			)
		)
		(property "Datasheet" "https://www.bourns.com/docs/product-datasheets/cr.pdf"
			(at 0 0 180)
			(layer "B.Fab")
			(hide yes)
			(effects
				(font
					(size 1.27 1.27)
					(thickness 0.15)
				)
				(justify mirror)
			)
		)
		(property "Description" "SMD Chip Resistor, 10 kohm, ± 1%, 62.5 mW, 0402 [1005 Metric], Thick Film, General Purpose"
			(at 0 0 180)
			(layer "B.Fab")
			(hide yes)
			(effects
				(font
					(size 1.27 1.27)
					(thickness 0.15)
				)
				(justify mirror)
			)
		)
		(property "MPN" "CR0402-FX-1002GLF"
			(at 0 0 0)
			(unlocked yes)
			(layer "B.Fab")
			(hide yes)
			(effects
				(font
					(size 1 1)
					(thickness 0.15)
				)
				(justify mirror)
			)
		)
		(property "Manufacturer" "Bourns"
			(at 0 0 0)
			(unlocked yes)
			(layer "B.Fab")
			(hide yes)
			(effects
				(font
					(size 1 1)
					(thickness 0.15)
				)
				(justify mirror)
			)
		)
		(property "License" "Apache-2.0"
			(at 0 0 0)
			(unlocked yes)
			(layer "B.Fab")
			(hide yes)
			(effects
				(font
					(size 1 1)
					(thickness 0.15)
				)
				(justify mirror)
			)
		)
		(property "Val" "10k"
			(at 0 0 0)
			(unlocked yes)
			(layer "B.Fab")
			(hide yes)
			(effects
				(font
					(size 1 1)
					(thickness 0.15)
				)
				(justify mirror)
			)
		)
		(property "Tolerance" "1%"
			(at 0 0 0)
			(unlocked yes)
			(layer "B.Fab")
			(hide yes)
			(effects
				(font
					(size 1 1)
					(thickness 0.15)
				)
				(justify mirror)
			)
		)
		(property "Author" "Antmicro"
			(at 0 0 0)
			(unlocked yes)
			(layer "B.Fab")
			(hide yes)
			(effects
				(font
					(size 1 1)
					(thickness 0.15)
				)
				(justify mirror)
			)
		)
		(sheetname "/TB Controller/")
		(sheetfile "tb.kicad_sch")
		(attr smd)
		(fp_rect
			(start -0.925 0.47)
			(end 0.925 -0.47)
			(stroke
				(width 0.05)
				(type default)
			)
			(fill no)
			(layer "B.CrtYd")
		)
		(fp_rect
			(start -0.5 0.25)
			(end 0.5 -0.25)
			(stroke
				(width 0.15)
				(type solid)
			)
			(fill no)
			(layer "B.Fab")
		)
		(fp_text user "${REFERENCE}"
			(at -0.95 -3.168 180)
			(layer "B.Fab")
			(effects
				(font
					(size 0.7 0.7)
					(thickness 0.15)
				)
				(justify left bottom mirror)
			)
		)
		(fp_text user "Author: Antmicro"
			(at -0.95 -4.169 180)
			(layer "B.Fab")
			(effects
				(font
					(size 0.7 0.7)
					(thickness 0.15)
				)
				(justify left bottom mirror)
			)
		)
		(fp_text user "License: Apache-2.0"
			(at -0.95 -5.169 180)
			(layer "B.Fab")
			(effects
				(font
					(size 0.7 0.7)
					(thickness 0.15)
				)
				(justify left bottom mirror)
			)
		)
		(pad "1" smd roundrect
			(at -0.48 0)
			(size 0.59 0.64)
			(layers "B.Cu" "B.Mask" "B.Paste")
			(roundrect_rratio 0.25)
			(net 189 "Net-(U4C-GPIO_6)")
			(pintype "passive")
		)
		(pad "2" smd roundrect
			(at 0.48 0)
			(size 0.59 0.64)
			(layers "B.Cu" "B.Mask" "B.Paste")
			(roundrect_rratio 0.25)
			(net 23 "GND")
			(pintype "passive")
		)
	)
	(footprint "antmicro-footprints:C_0402_1005Metric"
		(layer "B.Cu")
		(at 128.499999 126.875 90)
		(descr "Capacitor SMD 0402")
		(tags "capacitor SMD 0402")
		(property "Reference" "C81"
			(at 7.700002 21.900002 270)
			(layer "B.SilkS")
			(effects
				(font
					(size 0.7 0.7)
					(thickness 0.15)
				)
				(justify mirror)
			)
		)
		(property "Value" "C_1u_0402"
			(at -1.022927 -2.155213 270)
			(layer "B.Fab")
			(effects
				(font
					(size 0.7 0.7)
					(thickness 0.15)
				)
				(justify left bottom mirror)
			)
		)
		(property "Datasheet" "https://product.tdk.com/en/search/capacitor/ceramic/mlcc/info?part_no=C1005X6S1A105K050BC"
			(at 0 0 270)
			(layer "B.Fab")
			(hide yes)
			(effects
				(font
					(size 1.27 1.27)
					(thickness 0.15)
				)
				(justify mirror)
			)
		)
		(property "Description" "SMD Multilayer Ceramic Capacitor, 1 µF, 10 V, 0402 [1005 Metric], ± 10%, X6S, C"
			(at 0 0 270)
			(layer "B.Fab")
			(hide yes)
			(effects
				(font
					(size 1.27 1.27)
					(thickness 0.15)
				)
				(justify mirror)
			)
		)
		(property "MPN" "C1005X6S1A105K050BC"
			(at 0 0 90)
			(unlocked yes)
			(layer "B.Fab")
			(hide yes)
			(effects
				(font
					(size 1 1)
					(thickness 0.15)
				)
				(justify mirror)
			)
		)
		(property "Manufacturer" "TDK"
			(at 0 0 90)
			(unlocked yes)
			(layer "B.Fab")
			(hide yes)
			(effects
				(font
					(size 1 1)
					(thickness 0.15)
				)
				(justify mirror)
			)
		)
		(property "License" "Apache-2.0"
			(at 0 0 90)
			(unlocked yes)
			(layer "B.Fab")
			(hide yes)
			(effects
				(font
					(size 1 1)
					(thickness 0.15)
				)
				(justify mirror)
			)
		)
		(property "Val" "1u"
			(at 0 0 90)
			(unlocked yes)
			(layer "B.Fab")
			(hide yes)
			(effects
				(font
					(size 1 1)
					(thickness 0.15)
				)
				(justify mirror)
			)
		)
		(property "Voltage" ""
			(at 0 0 90)
			(unlocked yes)
			(layer "B.Fab")
			(hide yes)
			(effects
				(font
					(size 1 1)
					(thickness 0.15)
				)
				(justify mirror)
			)
		)
		(property "Dielectric" ""
			(at 0 0 90)
			(unlocked yes)
			(layer "B.Fab")
			(hide yes)
			(effects
				(font
					(size 1 1)
					(thickness 0.15)
				)
				(justify mirror)
			)
		)
		(property "Author" "Antmicro"
			(at 0 0 90)
			(unlocked yes)
			(layer "B.Fab")
			(hide yes)
			(effects
				(font
					(size 1 1)
					(thickness 0.15)
				)
				(justify mirror)
			)
		)
		(sheetname "/TB Controller - Power/")
		(sheetfile "tb-power.kicad_sch")
		(attr smd)
		(fp_rect
			(start -0.925 0.47)
			(end 0.925 -0.47)
			(stroke
				(width 0.05)
				(type default)
			)
			(fill no)
			(layer "B.CrtYd")
		)
		(fp_line
			(start 0.504 -0.248)
			(end -0.494 -0.248)
			(stroke
				(width 0.15)
				(type solid)
			)
			(layer "B.Fab")
		)
		(fp_line
			(start -0.494 -0.248)
			(end -0.494 0.25)
			(stroke
				(width 0.15)
				(type solid)
			)
			(layer "B.Fab")
		)
		(fp_line
			(start 0.504 0.25)
			(end 0.504 -0.248)
			(stroke
				(width 0.15)
				(type solid)
			)
			(layer "B.Fab")
		)
		(fp_line
			(start -0.494 0.25)
			(end 0.504 0.25)
			(stroke
				(width 0.15)
				(type solid)
			)
			(layer "B.Fab")
		)
		(fp_text user "${REFERENCE}"
			(at -0.939 -4.599 270)
			(layer "B.Fab")
			(effects
				(font
					(size 0.7 0.7)
					(thickness 0.15)
				)
				(justify left bottom mirror)
			)
		)
		(fp_text user "Author: Antmicro"
			(at -0.939 -3.399 270)
			(layer "B.Fab")
			(effects
				(font
					(size 0.7 0.7)
					(thickness 0.15)
				)
				(justify left bottom mirror)
			)
		)
		(fp_text user "License: Apache-2.0"
			(at -0.939 -5.799 270)
			(layer "B.Fab")
			(effects
				(font
					(size 0.7 0.7)
					(thickness 0.15)
				)
				(justify left bottom mirror)
			)
		)
		(pad "1" smd roundrect
			(at -0.48 0 90)
			(size 0.59 0.64)
			(layers "B.Cu" "B.Mask" "B.Paste")
			(roundrect_rratio 0.25)
			(net 23 "GND")
			(pintype "passive")
		)
		(pad "2" smd roundrect
			(at 0.48 0 90)
			(size 0.59 0.64)
			(layers "B.Cu" "B.Mask" "B.Paste")
			(roundrect_rratio 0.25)
			(net 180 "Net-(U4A-VCC0P9_LVR_SENSE)")
			(pintype "passive")
		)
	)
)
